# T6G (Grand Teton) — schematic netlist excerpt (pin names and nets, part order shuffled) for the footprints in the layout excerpt that follows; sources: Cadence DE-HDL packaged netlist, KiCad conversion of 04192023_DAF0TMB3IC0_F0TG_MB_C_brd_V02_OCP.brd

R6010  Q_RES  0 5% CHIP  pkg 0402LF  page 150 : A = SGPIO_SCM_DI_<0> ; B = SGPIO_SCM_DI_R_<0>
R1700  Q_RES  200K 1% CHIP  pkg 0402LF  page 148 : A = P3V3_AUX ; B = SMB_PCIE_M2_0_EN

(kicad_pcb
	(version 20260206)
	(generator "pcbnew")
	(generator_version "10.0")
	(general
		(thickness 1.6)
		(legacy_teardrops no)
	)
	(paper "A4")
	(title_block
		(title "04192023_DAF0TMB3IC0_F0TG_MB_C_brd_V02_OCP.brd")
		(comment 1 "Grand Teton / footprints 1382-1383 of 8354")
	)
	(layers
		(0 "F.Cu" signal "TOP")
		(4 "In1.Cu" signal "GND")
		(6 "In2.Cu" signal "IN1")
		(8 "In3.Cu" signal "GND1")
		(10 "In4.Cu" signal "IN2")
		(12 "In5.Cu" signal "GND2")
		(14 "In6.Cu" signal "IN3")
		(16 "In7.Cu" signal "GND3")
		(18 "In8.Cu" signal "VCC")
		(20 "In9.Cu" signal "VCC1")
		(22 "In10.Cu" signal "GND4")
		(24 "In11.Cu" signal "IN4")
		(26 "In12.Cu" signal "GND5")
		(28 "In13.Cu" signal "IN5")
		(30 "In14.Cu" signal "GND6")
		(32 "In15.Cu" signal "IN6")
		(34 "In16.Cu" signal "GND7")
		(2 "B.Cu" signal "BOTTOM")
		(9 "F.Adhes" user "F.Adhesive")
		(11 "B.Adhes" user "B.Adhesive")
		(13 "F.Paste" user "Package Geometry/Pastemask Top")
		(15 "B.Paste" user "Package Geometry/Pastemask Bottom")
		(5 "F.SilkS" user "Ref Des/Silkscreen Top")
		(7 "B.SilkS" user "Ref Des/Silkscreen Bottom")
		(1 "F.Mask" user "Board Geometry/Soldermask Top")
		(3 "B.Mask" user "Board Geometry/Soldermask Bottom")
		(17 "Dwgs.User" user "User.Drawings")
		(19 "Cmts.User" user "User.Comments")
		(21 "Eco1.User" user "User.Eco1")
		(23 "Eco2.User" user "User.Eco2")
		(25 "Edge.Cuts" user "Board Geometry/Outline")
		(27 "Margin" user)
		(31 "F.CrtYd" user "Package Geometry/Place Bound Top")
		(29 "B.CrtYd" user "Package Geometry/Place Bound Bottom")
		(35 "F.Fab" user "Ref Des/Assembly Top")
		(33 "B.Fab" user "Ref Des/Assembly Bottom")
	)
	(footprint ""
		(layer "F.Cu")
		(at 157.018228 -23.284942 -90)
		(property "Reference" "R6010"
			(at 0 0 270)
			(layer "F.SilkS")
			(hide yes)
			(effects
				(font
					(size 1.27 1.27)
				)
			)
		)
		(property "Value" ""
			(at 0 0 270)
			(layer "F.Fab")
			(effects
				(font
					(size 1.27 1.27)
				)
			)
		)
		(duplicate_pad_numbers_are_jumpers no)
		(fp_line
			(start -0.7874 0.4064)
			(end -0.7874 -0.4064)
			(stroke
				(width 0.1524)
				(type default)
			)
			(layer "F.SilkS")
		)
		(fp_line
			(start 0.7874 0.4064)
			(end -0.7874 0.4064)
			(stroke
				(width 0.1524)
				(type default)
			)
			(layer "F.SilkS")
		)
		(fp_line
			(start -0.7874 -0.4064)
			(end 0.7874 -0.4064)
			(stroke
				(width 0.1524)
				(type default)
			)
			(layer "F.SilkS")
		)
		(fp_line
			(start 0.7874 -0.4064)
			(end 0.7874 0.4064)
			(stroke
				(width 0.1524)
				(type default)
			)
			(layer "F.SilkS")
		)
		(fp_line
			(start -0.67945 0.3048)
			(end -0.67945 -0.305054)
			(stroke
				(width 0.1)
				(type default)
			)
			(layer "F.Fab")
		)
		(fp_line
			(start -0.12065 0.3048)
			(end -0.67945 0.3048)
			(stroke
				(width 0.1)
				(type default)
			)
			(layer "F.Fab")
		)
		(fp_line
			(start 0.120396 0.3048)
			(end 0.120396 0.2794)
			(stroke
				(width 0.1)
				(type default)
			)
			(layer "F.Fab")
		)
		(fp_line
			(start 0.67945 0.3048)
			(end 0.120396 0.3048)
			(stroke
				(width 0.1)
				(type default)
			)
			(layer "F.Fab")
		)
		(fp_line
			(start -0.12065 0.2794)
			(end -0.12065 0.3048)
			(stroke
				(width 0.1)
				(type default)
			)
			(layer "F.Fab")
		)
		(fp_line
			(start 0.120396 0.2794)
			(end -0.12065 0.2794)
			(stroke
				(width 0.1)
				(type default)
			)
			(layer "F.Fab")
		)
		(fp_line
			(start -0.12065 -0.2794)
			(end 0.12065 -0.2794)
			(stroke
				(width 0.1)
				(type default)
			)
			(layer "F.Fab")
		)
		(fp_line
			(start 0.12065 -0.2794)
			(end 0.12065 -0.3048)
			(stroke
				(width 0.1)
				(type default)
			)
			(layer "F.Fab")
		)
		(fp_line
			(start 0.12065 -0.3048)
			(end 0.67945 -0.3048)
			(stroke
				(width 0.1)
				(type default)
			)
			(layer "F.Fab")
		)
		(fp_line
			(start 0.67945 -0.3048)
			(end 0.67945 0.3048)
			(stroke
				(width 0.1)
				(type default)
			)
			(layer "F.Fab")
		)
		(fp_line
			(start -0.67945 -0.305054)
			(end -0.12065 -0.305054)
			(stroke
				(width 0.1)
				(type default)
			)
			(layer "F.Fab")
		)
		(fp_line
			(start -0.12065 -0.305054)
			(end -0.12065 -0.2794)
			(stroke
				(width 0.1)
				(type default)
			)
			(layer "F.Fab")
		)
		(pad "1" smd circle
			(at -0.40005 0 270)
			(size 0 0)
			(layers "F.Cu" "F.Mask" "F.Paste")
			(net "SGPIO_SCM_DI_<0>")
		)
		(pad "2" smd circle
			(at 0.40005 0 270)
			(size 0 0)
			(layers "F.Cu" "F.Mask" "F.Paste")
			(net "SGPIO_SCM_DI_R_<0>")
		)
	)
	(footprint ""
		(layer "F.Cu")
		(at 157.81274 -44.985686 -90)
		(property "Reference" "R1700"
			(at 0 0 270)
			(layer "F.SilkS")
			(hide yes)
			(effects
				(font
					(size 1.27 1.27)
				)
			)
		)
		(property "Value" ""
			(at 0 0 270)
			(layer "F.Fab")
			(effects
				(font
					(size 1.27 1.27)
				)
			)
		)
		(duplicate_pad_numbers_are_jumpers no)
		(fp_line
			(start -0.7874 0.4064)
			(end -0.7874 -0.4064)
			(stroke
				(width 0.1524)
				(type default)
			)
			(layer "F.SilkS")
		)
		(fp_line
			(start 0.7874 0.4064)
			(end -0.7874 0.4064)
			(stroke
				(width 0.1524)
				(type default)
			)
			(layer "F.SilkS")
		)
		(fp_line
			(start -0.7874 -0.4064)
			(end 0.7874 -0.4064)
			(stroke
				(width 0.1524)
				(type default)
			)
			(layer "F.SilkS")
		)
		(fp_line
			(start 0.7874 -0.4064)
			(end 0.7874 0.4064)
			(stroke
				(width 0.1524)
				(type default)
			)
			(layer "F.SilkS")
		)
		(fp_line
			(start -0.67945 0.3048)
			(end -0.67945 -0.305054)
			(stroke
				(width 0.1)
				(type default)
			)
			(layer "F.Fab")
		)
		(fp_line
			(start -0.12065 0.3048)
			(end -0.67945 0.3048)
			(stroke
				(width 0.1)
				(type default)
			)
			(layer "F.Fab")
		)
		(fp_line
			(start 0.120396 0.3048)
			(end 0.120396 0.2794)
			(stroke
				(width 0.1)
				(type default)
			)
			(layer "F.Fab")
		)
		(fp_line
			(start 0.67945 0.3048)
			(end 0.120396 0.3048)
			(stroke
				(width 0.1)
				(type default)
			)
			(layer "F.Fab")
		)
		(fp_line
			(start -0.12065 0.2794)
			(end -0.12065 0.3048)
			(stroke
				(width 0.1)
				(type default)
			)
			(layer "F.Fab")
		)
		(fp_line
			(start 0.120396 0.2794)
			(end -0.12065 0.2794)
			(stroke
				(width 0.1)
				(type default)
			)
			(layer "F.Fab")
		)
		(fp_line
			(start -0.12065 -0.2794)
			(end 0.12065 -0.2794)
			(stroke
				(width 0.1)
				(type default)
			)
			(layer "F.Fab")
		)
		(fp_line
			(start 0.12065 -0.2794)
			(end 0.12065 -0.3048)
			(stroke
				(width 0.1)
				(type default)
			)
			(layer "F.Fab")
		)
		(fp_line
			(start 0.12065 -0.3048)
			(end 0.67945 -0.3048)
			(stroke
				(width 0.1)
				(type default)
			)
			(layer "F.Fab")
		)
		(fp_line
			(start 0.67945 -0.3048)
			(end 0.67945 0.3048)
			(stroke
				(width 0.1)
				(type default)
			)
			(layer "F.Fab")
		)
		(fp_line
			(start -0.67945 -0.305054)
			(end -0.12065 -0.305054)
			(stroke
				(width 0.1)
				(type default)
			)
			(layer "F.Fab")
		)
		(fp_line
			(start -0.12065 -0.305054)
			(end -0.12065 -0.2794)
			(stroke
				(width 0.1)
				(type default)
			)
			(layer "F.Fab")
		)
		(pad "1" smd circle
			(at -0.40005 0 270)
			(size 0 0)
			(layers "F.Cu" "F.Mask" "F.Paste")
			(net "P3V3_AUX")
		)
		(pad "2" smd circle
			(at 0.40005 0 270)
			(size 0 0)
			(layers "F.Cu" "F.Mask" "F.Paste")
			(net "SMB_PCIE_M2_0_EN")
		)
	)
)
